# T6G (Grand Teton) — schematic parts with pin connectivity, parts 2628–2628 of 8303; source: Cadence DE-HDL packaged netlist (pstxprt.dat, pstxnet.dat, pstchip.dat)

J68  SCONN288_DDR506112002KQ  IO  pkg DDR288S_1-1VXC  page 95
  1  VIN_BULK0  POWER  = P12V_MEM_CPU0
  2  RFU0  TRI  = NC
  3  VIN_MGMT  POWER  = P3V3_AUX
  4  HSCL  IN  = I3C_SPD_DDRJ_CPU0_SCL
  5  HSDA  BI  = I3C_SPD_DDRJ_CPU0_SDA
  6  VSS0  POWER  = GND
  7  DQ0_A  BI  = M_J_CPU0_SA_DQ<0>
  8  VSS1  POWER  = GND
  9  DQ1_A  BI  = M_J_CPU0_SA_DQ<1>
  10  VSS2  POWER  = GND
  11  DQS0_A_T  BI  = M_J_CPU0_SA_DQS_DP<0>
  12  DQS0_A_C  BI  = M_J_CPU0_SA_DQS_DN<0>
  13  VSS3  POWER  = GND
  14  DQ4_A  BI  = M_J_CPU0_SA_DQ<4>
  15  VSS4  POWER  = GND
  16  DQ5_A  BI  = M_J_CPU0_SA_DQ<5>
  17  VSS5  POWER  = GND
  18  DQ8_A  BI  = M_J_CPU0_SA_DQ<8>
  19  VSS6  POWER  = GND
  20  DQ9_A  BI  = M_J_CPU0_SA_DQ<9>
  21  VSS7  POWER  = GND
  22  DQS1_A_T  BI  = M_J_CPU0_SA_DQS_DP<1>
  23  DQS1_A_C  BI  = M_J_CPU0_SA_DQS_DN<1>
  24  VSS8  POWER  = GND
  25  DQ12_A  BI  = M_J_CPU0_SA_DQ<12>
  26  VSS9  POWER  = GND
  27  DQ13_A  BI  = M_J_CPU0_SA_DQ<13>
  28  VSS10  POWER  = GND
  29  DQ16_A  BI  = M_J_CPU0_SA_DQ<16>
  30  VSS11  POWER  = GND
  31  DQ17_A  BI  = M_J_CPU0_SA_DQ<17>
  32  VSS12  POWER  = GND
  33  DQS2_A_T  BI  = M_J_CPU0_SA_DQS_DP<2>
  34  DQS2_A_C  BI  = M_J_CPU0_SA_DQS_DN<2>
  35  VSS13  POWER  = GND
  36  DQ20_A  BI  = M_J_CPU0_SA_DQ<20>
  37  VSS14  POWER  = GND
  38  DQ21_A  BI  = M_J_CPU0_SA_DQ<21>
  39  VSS15  POWER  = GND
  40  DQ24_A  BI  = M_J_CPU0_SA_DQ<24>
  41  VSS16  POWER  = GND
  42  DQ25_A  BI  = M_J_CPU0_SA_DQ<25>
  43  VSS17  POWER  = GND
  44  DQS3_A_T  BI  = M_J_CPU0_SA_DQS_DP<3>
  45  DQS3_A_C  BI  = M_J_CPU0_SA_DQS_DN<3>
  46  VSS18  POWER  = GND
  47  DQ28_A  BI  = M_J_CPU0_SA_DQ<28>
  48  VSS19  POWER  = GND
  49  DQ29_A  BI  = M_J_CPU0_SA_DQ<29>
  50  VSS20  POWER  = GND
  51  CB0_A  BI  = M_J_CPU0_SA_CB<0>
  52  VSS21  POWER  = GND
  53  CB1_A  BI  = M_J_CPU0_SA_CB<1>
  54  VSS22  POWER  = GND
  55  DQS4_A_T  BI  = M_J_CPU0_SA_DQS_DP<4>
  56  DQS4_A_C  BI  = M_J_CPU0_SA_DQS_DN<4>
  57  VSS23  POWER  = GND
  58  CB4_A  BI  = M_J_CPU0_SA_CB<4>
  59  VSS24  POWER  = GND
  60  CB5_A  BI  = M_J_CPU0_SA_CB<5>
  61  VSS25  POWER  = GND
  62  ALERT_N  OUT  = M_J_CPU0_ALERT_N
  63  VSS26  POWER  = GND
  64  CS0_A_N  IN  = M_J_CPU0_SA_CS_N<0>
  65  VSS27  POWER  = GND
  66  CA0_A  IN  = M_J_CPU0_SA_CA<0>
  67  VSS28  POWER  = GND
  68  CA2_A  IN  = M_J_CPU0_SA_CA<2>
  69  VSS29  POWER  = GND
  70  CA4_A  IN  = M_J_CPU0_SA_CA<4>
  71  VSS30  POWER  = GND
  72  CA6_A  IN  = M_J_CPU0_SA_CA<6>
  73  VSS31  POWER  = GND
  74  PAR_A  IN  = M_J_CPU0_SA_PAR
  75  VSS32  POWER  = GND
  76  CA0_B  IN  = M_J_CPU0_SB_CA<0>
  77  VSS33  POWER  = GND
  78  CA2_B  IN  = M_J_CPU0_SB_CA<2>
  79  VSS34  POWER  = GND
  80  CA4_B  IN  = M_J_CPU0_SB_CA<4>
  81  VSS35  POWER  = GND
  82  CA6_B  IN  = M_J_CPU0_SB_CA<6>
  83  VSS36  POWER  = GND
  84  CS0_B_N  IN  = M_J_CPU0_SB_CS_N<0>
  85  VSS37  POWER  = GND
  86  \lbd||rsp_a_n\  OUT  = M_J_CPU0_SA_RSP<0>
  87  \lbs||rsp_b_n\  OUT  = M_J_CPU0_SB_RSP<0>
  88  VSS38  POWER  = GND
  89  CB4_B  BI  = M_J_CPU0_SB_CB<4>
  90  VSS39  POWER  = GND
  91  CB5_B  BI  = M_J_CPU0_SB_CB<5>
  92  VSS40  POWER  = GND
  93  \dqs9_b_t||tdqs9_b_t||dbi4_b_n\  BI  = M_J_CPU0_SB_DQS_DP<9>
  94  \dqs9_b_c||tdqs9_b_c\  BI  = M_J_CPU0_SB_DQS_DN<9>
  95  VSS41  POWER  = GND
  96  CB0_B  BI  = M_J_CPU0_SB_CB<0>
  97  VSS42  POWER  = GND
  98  CB1_B  BI  = M_J_CPU0_SB_CB<1>
  99  VSS43  POWER  = GND
  100  DQ0_B  BI  = M_J_CPU0_SB_DQ<0>
  101  VSS44  POWER  = GND
  102  DQ1_B  BI  = M_J_CPU0_SB_DQ<1>
  103  VSS45  POWER  = GND
  104  DQS0_B_T  BI  = M_J_CPU0_SB_DQS_DP<0>
  105  DQS0_B_C  BI  = M_J_CPU0_SB_DQS_DN<0>
  106  VSS46  POWER  = GND
  107  DQ4_B  BI  = M_J_CPU0_SB_DQ<4>
  108  VSS47  POWER  = GND
  109  DQ5_B  BI  = M_J_CPU0_SB_DQ<5>
  110  VSS48  POWER  = GND
  111  DQ8_B  BI  = M_J_CPU0_SB_DQ<8>
  112  VSS49  POWER  = GND
  113  DQ9_B  BI  = M_J_CPU0_SB_DQ<9>
  114  VSS50  POWER  = GND
  115  DQS1_B_T  BI  = M_J_CPU0_SB_DQS_DP<1>
  116  DQS1_B_C  BI  = M_J_CPU0_SB_DQS_DN<1>
  117  VSS51  POWER  = GND
  118  DQ12_B  BI  = M_J_CPU0_SB_DQ<12>
  119  VSS52  POWER  = GND
  120  DQ13_B  BI  = M_J_CPU0_SB_DQ<13>
  121  VSS53  POWER  = GND
  122  DQ16_B  BI  = M_J_CPU0_SB_DQ<16>
  123  VSS54  POWER  = GND
  124  DQ17_B  BI  = M_J_CPU0_SB_DQ<17>
  125  VSS55  POWER  = GND
  126  DQS2_B_T  BI  = M_J_CPU0_SB_DQS_DP<2>
  127  DQS2_B_C  BI  = M_J_CPU0_SB_DQS_DN<2>
  128  VSS56  POWER  = GND
  129  DQ20_B  BI  = M_J_CPU0_SB_DQ<20>
  130  VSS57  POWER  = GND
  131  DQ21_B  BI  = M_J_CPU0_SB_DQ<21>
  132  VSS58  POWER  = GND
  133  DQ24_B  BI  = M_J_CPU0_SB_DQ<24>
  134  VSS59  POWER  = GND
  135  DQ25_B  BI  = M_J_CPU0_SB_DQ<25>
  136  VSS60  POWER  = GND
  137  DQS3_B_T  BI  = M_J_CPU0_SB_DQS_DP<3>
  138  DQS3_B_C  BI  = M_J_CPU0_SB_DQS_DN<3>
  139  VSS61  POWER  = GND
  140  DQ28_B  BI  = M_J_CPU0_SB_DQ<28>
  141  VSS62  POWER  = GND
  142  DQ29_B  BI  = M_J_CPU0_SB_DQ<29>
  143  VSS63  POWER  = GND
  144  RFU1  TRI  = NC
  145  VIN_BULK1  POWER  = P12V_MEM_CPU0
  146  VIN_BULK2  POWER  = P12V_MEM_CPU0
  147  \pwr_good||fail_n\  BI  = PWRGD_CHJ_CPU0_DIMM
  148  HAS  IN  = PD_CHJ_CPU0_DIMM_SAA
  149  RFU2  TRI  = NC
  150  RFU3  TRI  = NC
  151  VSS64  POWER  = GND
  152  DQ2_A  BI  = M_J_CPU0_SA_DQ<2>
  153  VSS65  POWER  = GND
  154  DQ3_A  BI  = M_J_CPU0_SA_DQ<3>
  155  VSS66  POWER  = GND
  156  \dqs5_a_c||tdqs5_a_c||dqs5_a_t||tdqs5_a_t\  BI  = M_J_CPU0_SA_DQS_DN<5>
  157  \dqs5_a_t||tdqs5_a_t\  BI  = M_J_CPU0_SA_DQS_DP<5>
  158  VSS67  POWER  = GND
  159  DQ6_A  BI  = M_J_CPU0_SA_DQ<6>
  160  VSS68  POWER  = GND
  161  DQ7_A  BI  = M_J_CPU0_SA_DQ<7>
  162  VSS69  POWER  = GND
  163  DQ10_A  BI  = M_J_CPU0_SA_DQ<10>
  164  VSS70  POWER  = GND
  165  DQ11_A  BI  = M_J_CPU0_SA_DQ<11>
  166  VSS71  POWER  = GND
  167  \dqs6_a_c||tdqs6_a_c||dqs6_a_t||tdqs6_a_t\  BI  = M_J_CPU0_SA_DQS_DN<6>
  168  \dqs6_a_t||tdqs6_a_t\  BI  = M_J_CPU0_SA_DQS_DP<6>
  169  VSS72  POWER  = GND
  170  DQ14_A  BI  = M_J_CPU0_SA_DQ<14>
  171  VSS73  POWER  = GND
  172  DQ15_A  BI  = M_J_CPU0_SA_DQ<15>
  173  VSS74  POWER  = GND
  174  DQ18_A  BI  = M_J_CPU0_SA_DQ<18>
  175  VSS75  POWER  = GND
  176  DQ19_A  BI  = M_J_CPU0_SA_DQ<19>
  177  VSS76  POWER  = GND
  178  \dqs7_a_c||tdqs7_a_c\  BI  = M_J_CPU0_SA_DQS_DN<7>
  179  \dqs7_a_t||tdqs7_a_t\  BI  = M_J_CPU0_SA_DQS_DP<7>
  180  VSS77  POWER  = GND
  181  DQ22_A  BI  = M_J_CPU0_SA_DQ<22>
  182  VSS78  POWER  = GND
  183  DQ23_A  BI  = M_J_CPU0_SA_DQ<23>
  184  VSS79  POWER  = GND
  185  DQ26_A  BI  = M_J_CPU0_SA_DQ<26>
  186  VSS80  POWER  = GND
  187  DQ27_A  BI  = M_J_CPU0_SA_DQ<27>
  188  VSS81  POWER  = GND
  189  \dqs8_a_c||tdqs8_a_c\  BI  = M_J_CPU0_SA_DQS_DN<8>
  190  \dqs8_a_t||tdqs8_a_t\  BI  = M_J_CPU0_SA_DQS_DP<8>
  191  VSS82  POWER  = GND
  192  DQ30_A  BI  = M_J_CPU0_SA_DQ<30>
  193  VSS83  POWER  = GND
  194  DQ31_A  BI  = M_J_CPU0_SA_DQ<31>
  195  VSS84  POWER  = GND
  196  CB2_A  BI  = M_J_CPU0_SA_CB<2>
  197  VSS85  POWER  = GND
  198  CB3_A  BI  = M_J_CPU0_SA_CB<3>
  199  VSS86  POWER  = GND
  200  \dqs9_a_c||tdqs9_a_c\  BI  = M_J_CPU0_SA_DQS_DN<9>
  201  \dqs9_a_t||tdqs9_a_t\  BI  = M_J_CPU0_SA_DQS_DP<9>
  202  VSS87  POWER  = GND
  203  CB6_A  BI  = M_J_CPU0_SA_CB<6>
  204  VSS88  POWER  = GND
  205  CB7_A  BI  = M_J_CPU0_SA_CB<7>
  206  VSS89  POWER  = GND
  207  RESET_N  IN  = M_J_CPU0_RESET_N
  208  VSS90  POWER  = GND
  209  CS1_A_N  IN  = M_J_CPU0_SA_CS_N<1>
  210  VSS91  POWER  = GND
  211  CA1_A  IN  = M_J_CPU0_SA_CA<1>
  212  VSS92  POWER  = GND
  213  CA3_A  IN  = M_J_CPU0_SA_CA<3>
  214  VSS93  POWER  = GND
  215  CA5_A  IN  = M_J_CPU0_SA_CA<5>
  216  VSS94  POWER  = GND
  217  CK_T  IN  = M_J_CPU0_CLK_DP<0>
  218  CK_C  IN  = M_J_CPU0_CLK_DN<0>
  219  VSS95  POWER  = GND
  220  RFU4  TRI  = NC
  221  CA1_B  IN  = M_J_CPU0_SB_CA<1>
  222  VSS96  POWER  = GND
  223  CA3_B  IN  = M_J_CPU0_SB_CA<3>
  224  VSS97  POWER  = GND
  225  CA5_B  IN  = M_J_CPU0_SB_CA<5>
  226  VSS98  POWER  = GND
  227  PAR_B  IN  = M_J_CPU0_SB_PAR
  228  VSS99  POWER  = GND
  229  CS1_B_N  IN  = M_J_CPU0_SB_CS_N<1>
  230  VSS100  POWER  = GND
  231  RFU5  TRI  = NC
  232  RFU6  TRI  = NC
  233  VSS101  POWER  = GND
  234  CB6_B  BI  = M_J_CPU0_SB_CB<6>
  235  VSS102  POWER  = GND
  236  CB7_B  BI  = M_J_CPU0_SB_CB<7>
  237  VSS103  POWER  = GND
  238  DQS4_B_C  BI  = M_J_CPU0_SB_DQS_DN<4>
  239  DQS4_B_T  BI  = M_J_CPU0_SB_DQS_DP<4>
  240  VSS104  POWER  = GND
  241  CB2_B  BI  = M_J_CPU0_SB_CB<2>
  242  VSS105  POWER  = GND
  243  CB3_B  BI  = M_J_CPU0_SB_CB<3>
  244  VSS106  POWER  = GND
  245  DQ2_B  BI  = M_J_CPU0_SB_DQ<2>
  246  VSS107  POWER  = GND
  247  DQ3_B  BI  = M_J_CPU0_SB_DQ<3>
  248  VSS108  POWER  = GND
  249  \dqs5_b_c||tdqs5_b_c\  BI  = M_J_CPU0_SB_DQS_DN<5>
  250  \dqs5_b_t||tdqs5_b_t\  BI  = M_J_CPU0_SB_DQS_DP<5>
  251  VSS109  POWER  = GND
  252  DQ6_B  BI  = M_J_CPU0_SB_DQ<6>
  253  VSS110  POWER  = GND
  254  DQ7_B  BI  = M_J_CPU0_SB_DQ<7>
  255  VSS111  POWER  = GND
  256  DQ10_B  BI  = M_J_CPU0_SB_DQ<10>
  257  VSS112  POWER  = GND
  258  DQ11_B  BI  = M_J_CPU0_SB_DQ<11>
  259  VSS113  POWER  = GND
  260  \dqs6_b_c||tdqs6_b_c\  BI  = M_J_CPU0_SB_DQS_DN<6>
  261  \dqs6_b_t||tdqs6_b_t\  BI  = M_J_CPU0_SB_DQS_DP<6>
  262  VSS114  POWER  = GND
  263  DQ14_B  BI  = M_J_CPU0_SB_DQ<14>
  264  VSS115  POWER  = GND
  265  DQ15_B  BI  = M_J_CPU0_SB_DQ<15>
  266  VSS116  POWER  = GND
  267  DQ18_B  BI  = M_J_CPU0_SB_DQ<18>
  268  VSS117  POWER  = GND
  269  DQ19_B  BI  = M_J_CPU0_SB_DQ<19>
  270  VSS118  POWER  = GND
  271  \dqs7_b_c||tdqs7_b_c\  BI  = M_J_CPU0_SB_DQS_DN<7>
  272  \dqs7_b_t||tdqs7_b_t\  BI  = M_J_CPU0_SB_DQS_DP<7>
  273  VSS119  POWER  = GND
  274  DQ22_B  BI  = M_J_CPU0_SB_DQ<22>
  275  VSS120  POWER  = GND
  276  DQ23_B  BI  = M_J_CPU0_SB_DQ<23>
  277  VSS121  POWER  = GND
  278  DQ26_B  BI  = M_J_CPU0_SB_DQ<26>
  279  VSS122  POWER  = GND
  280  DQ27_B  BI  = M_J_CPU0_SB_DQ<27>
  281  VSS123  POWER  = GND
  282  \dqs8_b_c||tdqs8_b_c\  BI  = M_J_CPU0_SB_DQS_DN<8>
  283  \dqs8_b_t||tdqs8_b_t\  BI  = M_J_CPU0_SB_DQS_DP<8>
  284  VSS124  POWER  = GND
  285  DQ30_B  BI  = M_J_CPU0_SB_DQ<30>
  286  VSS125  POWER  = GND
  287  DQ31_B  BI  = M_J_CPU0_SB_DQ<31>
  288  VSS126  POWER  = GND
  G1  G1  POWER  = GND
  G2  G2  POWER  = GND
  G3  G3  POWER  = GND
